# BASEBOARD_FAB2 (Tioga Pass) — schematic netlist excerpt (pin names and nets, part order shuffled) for the footprints in the layout excerpt that follows; sources: Cadence DE-HDL packaged netlist, KiCad conversion of Wiwynn_Tioga_Pass_MB.brd

R4P18  RES  49.9 1% CHIP  pkg 0402  page 21 : A = H_PM_SYNC_GTL_R1 ; B = H_PM_SYNC_GTL
C5P26  CAP  47UF 4V 20% X6S  pkg 0805  page 42 : A = PVCCIN_CPU0 ; B = GND
C1R19  CAP_A  0.1UF 16V 10% X7R  pkg 0402V  page 139 : A = P1V5_LAN ; B = GND

(kicad_pcb
	(version 20260206)
	(generator "pcbnew")
	(generator_version "10.0")
	(general
		(thickness 1.6)
		(legacy_teardrops no)
	)
	(paper "A4")
	(title_block
		(title "Wiwynn_Tioga_Pass_MB.brd")
		(comment 1 "Tioga Pass / footprints 4527-4529 of 4770")
	)
	(layers
		(0 "F.Cu" signal "TOP")
		(4 "In1.Cu" signal "L2GND")
		(6 "In2.Cu" signal "L3")
		(8 "In3.Cu" signal "L4GND")
		(10 "In4.Cu" signal "L5")
		(12 "In5.Cu" signal "L6GND")
		(14 "In6.Cu" signal "L7VCC")
		(16 "In7.Cu" signal "L8VCC")
		(18 "In8.Cu" signal "L9GND")
		(20 "In9.Cu" signal "L10")
		(22 "In10.Cu" signal "L11GND")
		(24 "In11.Cu" signal "L12")
		(26 "In12.Cu" signal "L13GND")
		(2 "B.Cu" signal "BOTTOM")
		(9 "F.Adhes" user "F.Adhesive")
		(11 "B.Adhes" user "B.Adhesive")
		(13 "F.Paste" user "Package Geometry/Pastemask Top")
		(15 "B.Paste" user "Package Geometry/Pastemask Bottom")
		(5 "F.SilkS" user "Ref Des/Silkscreen Top")
		(7 "B.SilkS" user "Ref Des/Silkscreen Bottom")
		(1 "F.Mask" user "Board Geometry/Soldermask Top")
		(3 "B.Mask" user "Board Geometry/Soldermask Bottom")
		(17 "Dwgs.User" user "User.Drawings")
		(19 "Cmts.User" user "User.Comments")
		(21 "Eco1.User" user "User.Eco1")
		(23 "Eco2.User" user "User.Eco2")
		(25 "Edge.Cuts" user "Board Geometry/Outline")
		(27 "Margin" user)
		(31 "F.CrtYd" user "Package Geometry/Place Bound Top")
		(29 "B.CrtYd" user "Package Geometry/Place Bound Bottom")
		(35 "F.Fab" user "Ref Des/Assembly Top")
		(33 "B.Fab" user "Ref Des/Assembly Bottom")
	)
	(footprint ""
		(layer "B.Cu")
		(at 295.8846 -68.154804)
		(property "Reference" "R4P18"
			(at 0 0 0)
			(layer "B.SilkS")
			(hide yes)
			(effects
				(font
					(size 1.27 1.27)
				)
				(justify mirror)
			)
		)
		(property "Value" ""
			(at 0 0 0)
			(layer "B.Fab")
			(effects
				(font
					(size 1.27 1.27)
				)
				(justify mirror)
			)
		)
		(duplicate_pad_numbers_are_jumpers no)
		(fp_poly
			(pts
				(xy 0.2794 -0.1016) (xy -0.2794 -0.1016) (xy -0.2794 0.9906) (xy 0.2794 0.9906)
			)
			(stroke
				(width 0)
				(type default)
			)
			(fill no)
			(layer "B.CrtYd")
		)
		(fp_line
			(start -0.2794 -0.1016)
			(end 0.2794 -0.1016)
			(stroke
				(width 0.1)
				(type default)
			)
			(layer "B.Fab")
		)
		(fp_line
			(start -0.2794 0.9906)
			(end -0.2794 -0.1016)
			(stroke
				(width 0.1)
				(type default)
			)
			(layer "B.Fab")
		)
		(fp_line
			(start 0.2794 -0.1016)
			(end 0.2794 0.9906)
			(stroke
				(width 0.1)
				(type default)
			)
			(layer "B.Fab")
		)
		(fp_line
			(start 0.2794 0.9906)
			(end -0.2794 0.9906)
			(stroke
				(width 0.1)
				(type default)
			)
			(layer "B.Fab")
		)
		(pad "1" smd rect
			(at 0 0 180)
			(size 0.508 0.508)
			(layers "B.Cu" "B.Mask" "B.Paste")
			(net "H_PM_SYNC_GTL_R1")
		)
		(pad "2" smd rect
			(at 0 0.889 180)
			(size 0.508 0.508)
			(layers "B.Cu" "B.Mask" "B.Paste")
			(net "H_PM_SYNC_GTL")
		)
		(zone
			(layer "B.Cu")
			(hatch none 0.5)
			(connect_pads
				(clearance 0)
			)
			(min_thickness 0.25)
			(keepout
				(tracks allowed)
				(vias not_allowed)
				(pads allowed)
				(copperpour not_allowed)
				(footprints allowed)
			)
			(placement
				(enabled no)
				(sheetname "")
			)
			(fill
				(thermal_gap 0.5)
				(thermal_bridge_width 0.5)
				(island_removal_mode 0)
			)
			(polygon
				(pts
					(xy 296.1386 -67.900804) (xy 295.6306 -67.900804) (xy 295.6306 -67.519804) (xy 296.1386 -67.519804)
				)
			)
		)
		(zone
			(layer "B.Cu")
			(hatch none 0.5)
			(connect_pads
				(clearance 0)
			)
			(min_thickness 0.25)
			(keepout
				(tracks not_allowed)
				(vias allowed)
				(pads allowed)
				(copperpour not_allowed)
				(footprints allowed)
			)
			(placement
				(enabled no)
				(sheetname "")
			)
			(fill
				(thermal_gap 0.5)
				(thermal_bridge_width 0.5)
				(island_removal_mode 0)
			)
			(polygon
				(pts
					(xy 296.1386 -67.519804) (xy 295.6306 -67.519804) (xy 295.6306 -67.900804) (xy 296.1386 -67.900804)
				)
			)
		)
	)
	(footprint ""
		(layer "B.Cu")
		(at 479.9711 -39.5224 90)
		(property "Reference" "C1R19"
			(at 0 0 90)
			(layer "B.SilkS")
			(hide yes)
			(effects
				(font
					(size 1.27 1.27)
				)
				(justify mirror)
			)
		)
		(property "Value" ""
			(at 0 0 90)
			(layer "B.Fab")
			(effects
				(font
					(size 1.27 1.27)
				)
				(justify mirror)
			)
		)
		(duplicate_pad_numbers_are_jumpers no)
		(fp_poly
			(pts
				(xy -0.3048 -0.1016) (xy -0.3048 0.9906) (xy 0.3048 0.9906) (xy 0.3048 -0.1016)
			)
			(stroke
				(width 0)
				(type default)
			)
			(fill no)
			(layer "B.CrtYd")
		)
		(fp_line
			(start 0.3048 -0.1016)
			(end 0.3048 0.9906)
			(stroke
				(width 0.1)
				(type default)
			)
			(layer "B.Fab")
		)
		(fp_line
			(start -0.3048 -0.1016)
			(end 0.3048 -0.1016)
			(stroke
				(width 0.1)
				(type default)
			)
			(layer "B.Fab")
		)
		(fp_line
			(start 0.3048 0.9906)
			(end -0.3048 0.9906)
			(stroke
				(width 0.1)
				(type default)
			)
			(layer "B.Fab")
		)
		(fp_line
			(start -0.3048 0.9906)
			(end -0.3048 -0.1016)
			(stroke
				(width 0.1)
				(type default)
			)
			(layer "B.Fab")
		)
		(pad "1" smd rect
			(at 0 0 270)
			(size 0.508 0.508)
			(layers "B.Cu" "B.Mask" "B.Paste")
			(net "P1V5_LAN")
		)
		(pad "2" smd rect
			(at 0 0.889 270)
			(size 0.508 0.508)
			(layers "B.Cu" "B.Mask" "B.Paste")
			(net "GND")
		)
		(zone
			(layer "B.Cu")
			(hatch none 0.5)
			(connect_pads
				(clearance 0)
			)
			(min_thickness 0.25)
			(keepout
				(tracks allowed)
				(vias not_allowed)
				(pads allowed)
				(copperpour not_allowed)
				(footprints allowed)
			)
			(placement
				(enabled no)
				(sheetname "")
			)
			(fill
				(thermal_gap 0.5)
				(thermal_bridge_width 0.5)
				(island_removal_mode 0)
			)
			(polygon
				(pts
					(xy 480.2251 -39.7764) (xy 480.2251 -39.2684) (xy 480.6061 -39.2684) (xy 480.6061 -39.7764)
				)
			)
		)
		(zone
			(layer "B.Cu")
			(hatch none 0.5)
			(connect_pads
				(clearance 0)
			)
			(min_thickness 0.25)
			(keepout
				(tracks not_allowed)
				(vias allowed)
				(pads allowed)
				(copperpour not_allowed)
				(footprints allowed)
			)
			(placement
				(enabled no)
				(sheetname "")
			)
			(fill
				(thermal_gap 0.5)
				(thermal_bridge_width 0.5)
				(island_removal_mode 0)
			)
			(polygon
				(pts
					(xy 480.6061 -39.7764) (xy 480.6061 -39.2684) (xy 480.2251 -39.2684) (xy 480.2251 -39.7764)
				)
			)
		)
	)
	(footprint ""
		(layer "B.Cu")
		(at 260.377686 -77.82814)
		(property "Reference" "C5P26"
			(at 0 0 0)
			(layer "B.SilkS")
			(hide yes)
			(effects
				(font
					(size 1.27 1.27)
				)
				(justify mirror)
			)
		)
		(property "Value" ""
			(at 0 0 0)
			(layer "B.Fab")
			(effects
				(font
					(size 1.27 1.27)
				)
				(justify mirror)
			)
		)
		(duplicate_pad_numbers_are_jumpers no)
		(fp_poly
			(pts
				(xy 0.7239 -0.2159) (xy -0.7239 -0.2159) (xy -0.7239 1.9939) (xy 0.7239 1.9939)
			)
			(stroke
				(width 0)
				(type default)
			)
			(fill no)
			(layer "B.CrtYd")
		)
		(fp_line
			(start -0.7239 -0.2159)
			(end 0.7239 -0.2159)
			(stroke
				(width 0.1)
				(type default)
			)
			(layer "B.Fab")
		)
		(fp_line
			(start -0.7239 1.9939)
			(end -0.7239 -0.2159)
			(stroke
				(width 0.1)
				(type default)
			)
			(layer "B.Fab")
		)
		(fp_line
			(start 0.7239 -0.2159)
			(end 0.7239 1.9939)
			(stroke
				(width 0.1)
				(type default)
			)
			(layer "B.Fab")
		)
		(fp_line
			(start 0.7239 1.9939)
			(end -0.7239 1.9939)
			(stroke
				(width 0.1)
				(type default)
			)
			(layer "B.Fab")
		)
		(pad "1" smd rect
			(at 0 0 180)
			(size 1.27 1.016)
			(layers "B.Cu" "B.Mask" "B.Paste")
			(net "PVCCIN_CPU0")
		)
		(pad "2" smd rect
			(at 0 1.778 180)
			(size 1.27 1.016)
			(layers "B.Cu" "B.Mask" "B.Paste")
			(net "GND")
		)
		(zone
			(layer "B.Cu")
			(hatch none 0.5)
			(connect_pads
				(clearance 0)
			)
			(min_thickness 0.25)
			(keepout
				(tracks not_allowed)
				(vias allowed)
				(pads allowed)
				(copperpour not_allowed)
				(footprints allowed)
			)
			(placement
				(enabled no)
				(sheetname "")
			)
			(fill
				(thermal_gap 0.5)
				(thermal_bridge_width 0.5)
				(island_removal_mode 0)
			)
			(polygon
				(pts
					(xy 261.012686 -77.32014) (xy 259.742686 -77.32014) (xy 259.742686 -76.55814) (xy 261.012686 -76.55814)
				)
			)
		)
	)
)
